(kicad_pcb
	(version 20260206)
	(generator "pcbnew")
	(generator_version "10.0")
	(general
		(thickness 1.6)
		(legacy_teardrops no)
	)
	(paper "A4")
	(title_block
		(title "fcb — Lightning_FCB_BRD.brd")
		(comment 1 "Lightning (Wiwynn / Facebook NVMe JBOF) / footprints 364-369 of 495")
	)
	(layers
		(0 "F.Cu" signal "TOP")
		(4 "In1.Cu" signal "L2GND")
		(6 "In2.Cu" signal "L3VCC")
		(2 "B.Cu" signal "BOTTOM")
		(9 "F.Adhes" user "F.Adhesive")
		(11 "B.Adhes" user "B.Adhesive")
		(13 "F.Paste" user "Package Geometry/Pastemask Top")
		(15 "B.Paste" user "Package Geometry/Pastemask Bottom")
		(5 "F.SilkS" user "Ref Des/Silkscreen Top")
		(7 "B.SilkS" user "Ref Des/Silkscreen Bottom")
		(1 "F.Mask" user "Board Geometry/Soldermask Top")
		(3 "B.Mask" user "Board Geometry/Soldermask Bottom")
		(17 "Dwgs.User" user "User.Drawings")
		(19 "Cmts.User" user "User.Comments")
		(21 "Eco1.User" user "User.Eco1")
		(23 "Eco2.User" user "User.Eco2")
		(25 "Edge.Cuts" user "Board Geometry/Outline")
		(27 "Margin" user)
		(31 "F.CrtYd" user "Package Geometry/Place Bound Top")
		(29 "B.CrtYd" user "Package Geometry/Place Bound Bottom")
		(35 "F.Fab" user "Ref Des/Assembly Top")
		(33 "B.Fab" user "Ref Des/Assembly Bottom")
	)
	(footprint ""
		(layer "F.Cu")
		(at 23.622 -367.411 -90)
		(property "Reference" "PR3"
			(at 0 0 270)
			(layer "F.SilkS")
			(hide yes)
			(effects
				(font
					(size 1.27 1.27)
				)
			)
		)
		(property "Value" "51K1R2F-GP"
			(at 0.064008 -3.993896 270)
			(unlocked yes)
			(layer "F.Fab")
			(hide yes)
			(effects
				(font
					(size 1.016 1.016)
					(thickness 0.1524)
				)
			)
		)
		(property "Device Type" "R402H16"
			(at 0.064008 -5.517896 270)
			(unlocked yes)
			(layer "F.Fab")
			(hide yes)
			(effects
				(font
					(size 1.016 1.016)
					(thickness 0.1524)
				)
			)
		)
		(duplicate_pad_numbers_are_jumpers no)
		(fp_line
			(start -0.508 -0.9398)
			(end -0.508 0.9398)
			(stroke
				(width 0.1524)
				(type default)
			)
			(layer "F.SilkS")
		)
		(fp_line
			(start 0.508 -0.9398)
			(end -0.508 -0.9398)
			(stroke
				(width 0.1524)
				(type default)
			)
			(layer "F.SilkS")
		)
		(fp_rect
			(start -0.508 0.9398)
			(end 0.508 -0.9398)
			(stroke
				(width 0)
				(type default)
			)
			(fill no)
			(layer "F.CrtYd")
		)
		(fp_rect
			(start -0.508 0.9398)
			(end 0.508 -0.9398)
			(stroke
				(width 0)
				(type default)
			)
			(fill no)
			(layer "F.Fab")
		)
		(pad "1" smd custom
			(at 0 -0.4445 270)
			(size 0.1397 0.1397)
			(layers "F.Cu" "F.Mask" "F.Paste")
			(net "ADM1276_ISET")
			(options
				(clearance outline)
				(anchor circle)
			)
			(primitives
				(gr_poly
					(pts
						(arc
							(start -0.1778 -0.2794)
							(mid -0.249642 -0.249642)
							(end -0.2794 -0.1778)
						)
						(arc
							(start -0.2794 0.1778)
							(mid -0.249642 0.249642)
							(end -0.1778 0.2794)
						)
						(arc
							(start 0.1778 0.2794)
							(mid 0.249642 0.249642)
							(end 0.2794 0.1778)
						)
						(arc
							(start 0.2794 -0.1778)
							(mid 0.249642 -0.249642)
							(end 0.1778 -0.2794)
						)
					)
					(width 0)
					(fill yes)
				)
			)
		)
		(pad "2" smd custom
			(at 0 0.4445 270)
			(size 0.1397 0.1397)
			(layers "F.Cu" "F.Mask" "F.Paste")
			(net "GND")
			(options
				(clearance outline)
				(anchor circle)
			)
			(primitives
				(gr_poly
					(pts
						(arc
							(start -0.1778 -0.2794)
							(mid -0.249642 -0.249642)
							(end -0.2794 -0.1778)
						)
						(arc
							(start -0.2794 0.1778)
							(mid -0.249642 0.249642)
							(end -0.1778 0.2794)
						)
						(arc
							(start 0.1778 0.2794)
							(mid 0.249642 0.249642)
							(end 0.2794 0.1778)
						)
						(arc
							(start 0.2794 -0.1778)
							(mid 0.249642 -0.249642)
							(end 0.1778 -0.2794)
						)
					)
					(width 0)
					(fill yes)
				)
			)
		)
	)
	(footprint ""
		(layer "F.Cu")
		(at 43.2308 -158.8516)
		(property "Reference" "R51"
			(at 0 0 0)
			(layer "F.SilkS")
			(hide yes)
			(effects
				(font
					(size 1.27 1.27)
				)
			)
		)
		(property "Value" "0R2J-2-GP"
			(at 0.064008 -3.993896 0)
			(unlocked yes)
			(layer "F.Fab")
			(hide yes)
			(effects
				(font
					(size 1.016 1.016)
					(thickness 0.1524)
				)
			)
		)
		(property "Device Type" "R402H16"
			(at 0.064008 -5.517896 0)
			(unlocked yes)
			(layer "F.Fab")
			(hide yes)
			(effects
				(font
					(size 1.016 1.016)
					(thickness 0.1524)
				)
			)
		)
		(duplicate_pad_numbers_are_jumpers no)
		(fp_line
			(start -0.508 -0.9398)
			(end -0.508 0.9398)
			(stroke
				(width 0.1524)
				(type default)
			)
			(layer "F.SilkS")
		)
		(fp_line
			(start 0.508 -0.9398)
			(end -0.508 -0.9398)
			(stroke
				(width 0.1524)
				(type default)
			)
			(layer "F.SilkS")
		)
		(fp_rect
			(start -0.508 0.9398)
			(end 0.508 -0.9398)
			(stroke
				(width 0)
				(type default)
			)
			(fill no)
			(layer "F.CrtYd")
		)
		(fp_rect
			(start -0.508 0.9398)
			(end 0.508 -0.9398)
			(stroke
				(width 0)
				(type default)
			)
			(fill no)
			(layer "F.Fab")
		)
		(pad "1" smd custom
			(at 0 -0.4445)
			(size 0.1397 0.1397)
			(layers "F.Cu" "F.Mask" "F.Paste")
			(net "NCT7904_VSEN_P12V_AUX")
			(options
				(clearance outline)
				(anchor circle)
			)
			(primitives
				(gr_poly
					(pts
						(arc
							(start -0.1778 -0.2794)
							(mid -0.249642 -0.249642)
							(end -0.2794 -0.1778)
						)
						(arc
							(start -0.2794 0.1778)
							(mid -0.249642 0.249642)
							(end -0.1778 0.2794)
						)
						(arc
							(start 0.1778 0.2794)
							(mid 0.249642 0.249642)
							(end 0.2794 0.1778)
						)
						(arc
							(start 0.2794 -0.1778)
							(mid 0.249642 -0.249642)
							(end 0.1778 -0.2794)
						)
					)
					(width 0)
					(fill yes)
				)
			)
		)
		(pad "2" smd custom
			(at 0 0.4445)
			(size 0.1397 0.1397)
			(layers "F.Cu" "F.Mask" "F.Paste")
			(net "NCT7904_VSEN9")
			(options
				(clearance outline)
				(anchor circle)
			)
			(primitives
				(gr_poly
					(pts
						(arc
							(start -0.1778 -0.2794)
							(mid -0.249642 -0.249642)
							(end -0.2794 -0.1778)
						)
						(arc
							(start -0.2794 0.1778)
							(mid -0.249642 0.249642)
							(end -0.1778 0.2794)
						)
						(arc
							(start 0.1778 0.2794)
							(mid 0.249642 0.249642)
							(end 0.2794 0.1778)
						)
						(arc
							(start 0.2794 -0.1778)
							(mid 0.249642 -0.249642)
							(end 0.1778 -0.2794)
						)
					)
					(width 0)
					(fill yes)
				)
			)
		)
	)
	(footprint ""
		(layer "F.Cu")
		(at 33.069784 -353.6442 -90)
		(property "Reference" "C259"
			(at 0 0 270)
			(layer "F.SilkS")
			(hide yes)
			(effects
				(font
					(size 1.27 1.27)
				)
			)
		)
		(property "Value" "SC10U25V6KX-1GP"
			(at -0.0762 -5.1308 270)
			(unlocked yes)
			(layer "F.Fab")
			(hide yes)
			(effects
				(font
					(size 1.016 1.016)
					(thickness 0.1524)
				)
			)
		)
		(property "Device Type" "C1206H71"
			(at -0.127 -6.6548 270)
			(unlocked yes)
			(layer "F.Fab")
			(hide yes)
			(effects
				(font
					(size 1.016 1.016)
					(thickness 0.1524)
				)
			)
		)
		(duplicate_pad_numbers_are_jumpers no)
		(fp_line
			(start -1.016 2.2352)
			(end -1.016 0.8382)
			(stroke
				(width 0.1524)
				(type default)
			)
			(layer "F.SilkS")
		)
		(fp_line
			(start 1.016 2.2352)
			(end -1.016 2.2352)
			(stroke
				(width 0.1524)
				(type default)
			)
			(layer "F.SilkS")
		)
		(fp_line
			(start 1.016 0.8382)
			(end 1.016 2.2352)
			(stroke
				(width 0.1524)
				(type default)
			)
			(layer "F.SilkS")
		)
		(fp_line
			(start -1.016 -0.8382)
			(end -1.016 -2.2352)
			(stroke
				(width 0.1524)
				(type default)
			)
			(layer "F.SilkS")
		)
		(fp_line
			(start -1.016 -2.2352)
			(end 1.016 -2.2352)
			(stroke
				(width 0.1524)
				(type default)
			)
			(layer "F.SilkS")
		)
		(fp_line
			(start 1.016 -2.2352)
			(end 1.016 -0.8382)
			(stroke
				(width 0.1524)
				(type default)
			)
			(layer "F.SilkS")
		)
		(fp_rect
			(start -1.0922 2.3114)
			(end 1.0922 -2.3114)
			(stroke
				(width 0)
				(type default)
			)
			(fill no)
			(layer "F.CrtYd")
		)
		(fp_poly
			(pts
				(xy 1.0922 -2.3114) (xy 1.0922 2.3114) (xy -1.0922 2.3114) (xy -1.0922 -2.3114)
			)
			(stroke
				(width 0)
				(type default)
			)
			(fill no)
			(layer "F.Fab")
		)
		(pad "1" smd rect
			(at 0 -1.397 270)
			(size 1.651 1.27)
			(layers "F.Cu" "F.Mask" "F.Paste")
			(net "OTP_RETRY_G")
		)
		(pad "2" smd rect
			(at 0 1.397 270)
			(size 1.651 1.27)
			(layers "F.Cu" "F.Mask" "F.Paste")
			(net "GND")
		)
	)
	(footprint ""
		(layer "F.Cu")
		(at 41.91 -350.647 90)
		(property "Reference" "JP1"
			(at 0 0 90)
			(layer "F.SilkS")
			(hide yes)
			(effects
				(font
					(size 1.27 1.27)
				)
			)
		)
		(property "Value" "PIN-CON3-S3-GP"
			(at -5.8039 -0.0889 90)
			(unlocked yes)
			(layer "F.Fab")
			(hide yes)
			(effects
				(font
					(size 1.016 1.016)
					(thickness 0.1524)
				)
			)
		)
		(property "Device Type" "21S-H91-03GB31"
			(at -5.8039 -1.6129 90)
			(unlocked yes)
			(layer "F.Fab")
			(hide yes)
			(effects
				(font
					(size 1.016 1.016)
					(thickness 0.1524)
				)
			)
		)
		(duplicate_pad_numbers_are_jumpers no)
		(fp_line
			(start -4.064 -1.6256)
			(end -2.794 -1.6256)
			(stroke
				(width 0.4064)
				(type default)
			)
			(layer "F.SilkS")
		)
		(fp_line
			(start 3.937 -1.4986)
			(end -3.937 -1.4986)
			(stroke
				(width 0.1524)
				(type default)
			)
			(layer "F.SilkS")
		)
		(fp_line
			(start -3.937 -1.4986)
			(end -3.937 1.4986)
			(stroke
				(width 0.1524)
				(type default)
			)
			(layer "F.SilkS")
		)
		(fp_line
			(start -4.064 -0.3556)
			(end -4.064 -1.6256)
			(stroke
				(width 0.4064)
				(type default)
			)
			(layer "F.SilkS")
		)
		(fp_line
			(start 3.937 1.4986)
			(end 3.937 -1.4986)
			(stroke
				(width 0.1524)
				(type default)
			)
			(layer "F.SilkS")
		)
		(fp_line
			(start -3.937 1.4986)
			(end 3.937 1.4986)
			(stroke
				(width 0.1524)
				(type default)
			)
			(layer "F.SilkS")
		)
		(fp_circle
			(center 2.54 0)
			(end 2.54 1.0668)
			(stroke
				(width 0.3048)
				(type default)
			)
			(fill no)
			(layer "F.SilkS")
		)
		(fp_circle
			(center 0 0)
			(end 0 1.0668)
			(stroke
				(width 0.3048)
				(type default)
			)
			(fill no)
			(layer "F.SilkS")
		)
		(fp_circle
			(center -2.54 0)
			(end -2.54 1.0668)
			(stroke
				(width 0.3048)
				(type default)
			)
			(fill no)
			(layer "F.SilkS")
		)
		(fp_rect
			(start -3.683 1.2446)
			(end 3.683 -1.2446)
			(stroke
				(width 0)
				(type default)
			)
			(fill no)
			(layer "F.CrtYd")
		)
		(fp_poly
			(pts
				(xy 4.191 -1.2446) (xy -3.683 -1.2446) (xy -3.683 1.2446) (xy 3.683 1.2446) (xy 3.683 -1.2319) (xy 4.191 -1.2319)
				(xy 4.191 1.7526) (xy -4.191 1.7526) (xy -4.191 -1.7526) (xy 4.191 -1.7526)
			)
			(stroke
				(width 0)
				(type default)
			)
			(fill no)
			(layer "F.CrtYd")
		)
		(fp_rect
			(start -4.191 1.7526)
			(end 4.191 -1.7526)
			(stroke
				(width 0)
				(type default)
			)
			(fill no)
			(layer "F.Fab")
		)
		(pad "1" thru_hole circle
			(at -2.54 0 90)
			(size 1.4224 1.4224)
			(drill 1.016)
			(layers "*.Cu" "*.Mask")
			(remove_unused_layers no)
			(net "TEMP_ALM#_JP_1")
			(clearance 0.1524)
			(thermal_gap 0.1524)
		)
		(pad "2" thru_hole circle
			(at 0 0 90)
			(size 1.4224 1.4224)
			(drill 1.016)
			(layers "*.Cu" "*.Mask")
			(remove_unused_layers no)
			(net "TEMP_ALM#_JP_2")
			(clearance 0.1524)
			(thermal_gap 0.1524)
		)
		(pad "3" thru_hole circle
			(at 2.54 0 90)
			(size 1.4224 1.4224)
			(drill 1.016)
			(layers "*.Cu" "*.Mask")
			(remove_unused_layers no)
			(net "OTP_RETRY_B")
			(clearance 0.1524)
			(thermal_gap 0.1524)
		)
	)
	(footprint ""
		(layer "F.Cu")
		(at 38.354 -378.333 180)
		(property "Reference" "PR28"
			(at 0 0 180)
			(layer "F.SilkS")
			(hide yes)
			(effects
				(font
					(size 1.27 1.27)
				)
			)
		)
		(property "Value" "10R2F-L-GP"
			(at 0.064008 -3.993896 180)
			(unlocked yes)
			(layer "F.Fab")
			(hide yes)
			(effects
				(font
					(size 1.016 1.016)
					(thickness 0.1524)
				)
			)
		)
		(property "Device Type" "R402H14"
			(at 0.064008 -5.517896 180)
			(unlocked yes)
			(layer "F.Fab")
			(hide yes)
			(effects
				(font
					(size 1.016 1.016)
					(thickness 0.1524)
				)
			)
		)
		(duplicate_pad_numbers_are_jumpers no)
		(fp_line
			(start 0.508 -0.9398)
			(end -0.508 -0.9398)
			(stroke
				(width 0.1524)
				(type default)
			)
			(layer "F.SilkS")
		)
		(fp_line
			(start -0.508 -0.9398)
			(end -0.508 0.9398)
			(stroke
				(width 0.1524)
				(type default)
			)
			(layer "F.SilkS")
		)
		(fp_rect
			(start -0.508 0.9398)
			(end 0.508 -0.9398)
			(stroke
				(width 0)
				(type default)
			)
			(fill no)
			(layer "F.CrtYd")
		)
		(fp_rect
			(start -0.508 0.9398)
			(end 0.508 -0.9398)
			(stroke
				(width 0)
				(type default)
			)
			(fill no)
			(layer "F.Fab")
		)
		(pad "1" smd custom
			(at 0 -0.4445 180)
			(size 0.1397 0.1397)
			(layers "F.Cu" "F.Mask" "F.Paste")
			(net "ADM1276_GATE")
			(options
				(clearance outline)
				(anchor circle)
			)
			(primitives
				(gr_poly
					(pts
						(arc
							(start -0.1778 -0.2794)
							(mid -0.249642 -0.249642)
							(end -0.2794 -0.1778)
						)
						(arc
							(start -0.2794 0.1778)
							(mid -0.249642 0.249642)
							(end -0.1778 0.2794)
						)
						(arc
							(start 0.1778 0.2794)
							(mid 0.249642 0.249642)
							(end 0.2794 0.1778)
						)
						(arc
							(start 0.2794 -0.1778)
							(mid 0.249642 -0.249642)
							(end 0.1778 -0.2794)
						)
					)
					(width 0)
					(fill yes)
				)
			)
		)
		(pad "2" smd custom
			(at 0 0.4445 180)
			(size 0.1397 0.1397)
			(layers "F.Cu" "F.Mask" "F.Paste")
			(net "ADM1276_GATE_DRV3")
			(options
				(clearance outline)
				(anchor circle)
			)
			(primitives
				(gr_poly
					(pts
						(arc
							(start -0.1778 -0.2794)
							(mid -0.249642 -0.249642)
							(end -0.2794 -0.1778)
						)
						(arc
							(start -0.2794 0.1778)
							(mid -0.249642 0.249642)
							(end -0.1778 0.2794)
						)
						(arc
							(start 0.1778 0.2794)
							(mid 0.249642 0.249642)
							(end 0.2794 0.1778)
						)
						(arc
							(start 0.2794 -0.1778)
							(mid 0.249642 -0.249642)
							(end 0.1778 -0.2794)
						)
					)
					(width 0)
					(fill yes)
				)
			)
		)
	)
	(footprint ""
		(layer "F.Cu")
		(at 26.227024 -173.96841 90)
		(property "Reference" "U2"
			(at 0 0 90)
			(layer "F.SilkS")
			(hide yes)
			(effects
				(font
					(size 1.27 1.27)
				)
			)
		)
		(property "Value" "NCT7368S-GP"
			(at 3.8989 1.5748 90)
			(unlocked yes)
			(layer "F.Fab")
			(hide yes)
			(effects
				(font
					(size 1.016 1.016)
					(thickness 0.1524)
				)
			)
		)
		(property "Device Type" "SOIC8-G3627H69"
			(at 3.8989 0.0508 90)
			(unlocked yes)
			(layer "F.Fab")
			(hide yes)
			(effects
				(font
					(size 1.016 1.016)
					(thickness 0.1524)
				)
			)
		)
		(duplicate_pad_numbers_are_jumpers no)
		(fp_line
			(start 2.7178 -3.6322)
			(end 2.7178 3.6322)
			(stroke
				(width 0.1524)
				(type default)
			)
			(layer "F.SilkS")
		)
		(fp_line
			(start -2.8829 -3.6322)
			(end 2.7178 -3.6322)
			(stroke
				(width 0.1524)
				(type default)
			)
			(layer "F.SilkS")
		)
		(fp_line
			(start -2.8829 -0.6223)
			(end -2.2479 0.0127)
			(stroke
				(width 0.1524)
				(type default)
			)
			(layer "F.SilkS")
		)
		(fp_line
			(start -2.2479 0.0127)
			(end -2.8829 0.6477)
			(stroke
				(width 0.1524)
				(type default)
			)
			(layer "F.SilkS")
		)
		(fp_line
			(start -2.8829 0.6477)
			(end -2.8829 -0.6223)
			(stroke
				(width 0.1524)
				(type default)
			)
			(layer "F.SilkS")
		)
		(fp_line
			(start 2.7178 3.6322)
			(end -2.8829 3.6322)
			(stroke
				(width 0.1524)
				(type default)
			)
			(layer "F.SilkS")
		)
		(fp_line
			(start -2.7051 3.6322)
			(end -2.7051 1.5494)
			(stroke
				(width 0.508)
				(type default)
			)
			(layer "F.SilkS")
		)
		(fp_line
			(start -2.8829 3.6322)
			(end -2.8829 -3.6322)
			(stroke
				(width 0.1524)
				(type default)
			)
			(layer "F.SilkS")
		)
		(fp_poly
			(pts
				(xy 0.2794 -0.2794) (xy 1.8034 -0.2794) (xy 1.8034 -1.3462) (xy 0.2794 -1.3462)
			)
			(stroke
				(width 0)
				(type default)
			)
			(fill yes)
			(layer "F.Paste")
		)
		(fp_poly
			(pts
				(xy -1.8034 -0.2794) (xy -0.2794 -0.2794) (xy -0.2794 -1.3462) (xy -1.8034 -1.3462)
			)
			(stroke
				(width 0)
				(type default)
			)
			(fill yes)
			(layer "F.Paste")
		)
		(fp_poly
			(pts
				(xy 0.2794 1.3462) (xy 1.8034 1.3462) (xy 1.8034 0.2794) (xy 0.2794 0.2794)
			)
			(stroke
				(width 0)
				(type default)
			)
			(fill yes)
			(layer "F.Paste")
		)
		(fp_poly
			(pts
				(xy -1.8034 1.3462) (xy -0.2794 1.3462) (xy -0.2794 0.2794) (xy -1.8034 0.2794)
			)
			(stroke
				(width 0)
				(type default)
			)
			(fill yes)
			(layer "F.Paste")
		)
		(fp_poly
			(pts
				(xy -2.1209 2.9972) (xy -2.1209 1.9558) (xy -2.4511 1.9558) (xy -2.4511 -1.9558) (xy -2.1209 -1.9558)
				(xy -2.1209 -2.9972) (xy 2.1209 -2.9972) (xy 2.1209 -1.9558) (xy 2.4511 -1.9558) (xy 2.4511 1.9558)
				(xy 2.1209 1.9558) (xy 2.1209 2.9972)
			)
			(stroke
				(width 0)
				(type default)
			)
			(fill no)
			(layer "F.CrtYd")
		)
		(fp_poly
			(pts
				(xy -2.9591 3.8862) (xy -2.9591 -3.8862) (xy 2.9591 -3.8862) (xy 2.9591 1.95072) (xy 2.4511 1.95072)
				(xy 2.4511 -1.9558) (xy 2.1209 -1.9558) (xy 2.1209 -2.9972) (xy -2.1209 -2.9972) (xy -2.1209 -1.9558)
				(xy -2.4511 -1.9558) (xy -2.4511 1.9558) (xy -2.1209 1.9558) (xy -2.1209 2.9972) (xy 2.1209 2.9972)
				(xy 2.1209 1.9558) (xy 2.9591 1.9558) (xy 2.9591 3.8862)
			)
			(stroke
				(width 0)
				(type default)
			)
			(fill no)
			(layer "F.CrtYd")
		)
		(fp_rect
			(start -2.9591 3.8862)
			(end 2.9591 -3.8862)
			(stroke
				(width 0)
				(type default)
			)
			(fill no)
			(layer "F.Fab")
		)
		(pad "1" smd rect
			(at -1.905 2.5527 90)
			(size 0.635 1.651)
			(layers "F.Cu" "F.Mask" "F.Paste")
			(net "P3V3")
		)
		(pad "2" smd rect
			(at -0.635 2.5527 90)
			(size 0.635 1.651)
			(layers "F.Cu" "F.Mask" "F.Paste")
			(net "PWM_EXP_1A")
		)
		(pad "3" smd rect
			(at 0.635 2.5527 90)
			(size 0.635 1.651)
			(layers "F.Cu" "F.Mask" "F.Paste")
			(net "PWM_EXP_1B")
		)
		(pad "4" smd rect
			(at 1.905 2.5527 90)
			(size 0.635 1.651)
			(layers "F.Cu" "F.Mask" "F.Paste")
			(net "PWM_EXP_2A")
		)
		(pad "5" smd rect
			(at 1.905 -2.5527 90)
			(size 0.635 1.651)
			(layers "F.Cu" "F.Mask" "F.Paste")
			(net "NCT7368S_SEL")
		)
		(pad "6" smd rect
			(at 0.635 -2.5527 90)
			(size 0.635 1.651)
			(layers "F.Cu" "F.Mask" "F.Paste")
			(net "THERMHOT#")
		)
		(pad "7" smd rect
			(at -0.635 -2.5527 90)
			(size 0.635 1.651)
			(layers "F.Cu" "F.Mask" "F.Paste")
			(net "PWM_OUT")
		)
		(pad "8" smd rect
			(at -1.905 -2.5527 90)
			(size 0.635 1.651)
			(layers "F.Cu" "F.Mask" "F.Paste")
			(net "PWM_EXP_2B")
		)
		(pad "9" smd rect
			(at 0 0 90)
			(size 3.6068 2.6924)
			(layers "F.Cu" "F.Mask" "F.Paste")
			(net "GND")
		)
	)
)
